# S9S_MB_2U (Grand Teton) — schematic netlist excerpt (pin names and nets, part order shuffled) for the footprints in the layout excerpt that follows; sources: Cadence DE-HDL packaged netlist, KiCad conversion of 03242023_DA0F0TMBIJ0_F0T_Motherboard_J_brd_V01_OCP.brd

J24  SCONN288_ADR50017P087CC  SCONN288_ADR50017-P087CC IO  pkg DDR288S_1-1VXB  page 105
  VIN_BULK0  = P12V_S3_AUX_CPU1_NVDIMM
  RFU0  = TP_CHD_CPU1_DIMM2_FRU_0
  VIN_MGMT  = P3V3_AUX
  HSCL  = I3C_SPD_DDRABCD_CPU1_LVC1_SCL_7
  HSDA  = I3C_SPD_DDRABCD_CPU1_LVC1_SDA
  VSS0  = GND
  DQ0_A  = M_D_CPU1_SA_DQ<0>
  VSS1  = GND
  DQ1_A  = M_D_CPU1_SA_DQ<1>
  VSS2  = GND
  DQS0_A_T  = M_D_CPU1_SA_DQS_DP<0>
  DQS0_A_C  = M_D_CPU1_SA_DQS_DN<0>
  VSS3  = GND
  DQ4_A  = M_D_CPU1_SA_DQ<4>
  VSS4  = GND
  DQ5_A  = M_D_CPU1_SA_DQ<5>
  VSS5  = GND
  DQ8_A  = M_D_CPU1_SA_DQ<8>
  VSS6  = GND
  DQ9_A  = M_D_CPU1_SA_DQ<9>
  VSS7  = GND
  DQS1_A_T  = M_D_CPU1_SA_DQS_DP<1>
  DQS1_A_C  = M_D_CPU1_SA_DQS_DN<1>
  VSS8  = GND
  DQ12_A  = M_D_CPU1_SA_DQ<12>
  VSS9  = GND
  DQ13_A  = M_D_CPU1_SA_DQ<13>
  VSS10  = GND
  DQ16_A  = M_D_CPU1_SA_DQ<16>
  VSS11  = GND
  DQ17_A  = M_D_CPU1_SA_DQ<17>
  VSS12  = GND
  DQS2_A_T  = M_D_CPU1_SA_DQS_DP<2>
  DQS2_A_C  = M_D_CPU1_SA_DQS_DN<2>
  VSS13  = GND
  DQ20_A  = M_D_CPU1_SA_DQ<20>
  VSS14  = GND
  DQ21_A  = M_D_CPU1_SA_DQ<21>
  VSS15  = GND
  DQ24_A  = M_D_CPU1_SA_DQ<24>
  VSS16  = GND
  DQ25_A  = M_D_CPU1_SA_DQ<25>
  VSS17  = GND
  DQS3_A_T  = M_D_CPU1_SA_DQS_DP<3>
  DQS3_A_C  = M_D_CPU1_SA_DQS_DN<3>
  VSS18  = GND
  DQ28_A  = M_D_CPU1_SA_DQ<28>
  VSS19  = GND
  DQ29_A  = M_D_CPU1_SA_DQ<29>
  VSS20  = GND
  CB0_A  = M_D_CPU1_SA_CB<0>
  VSS21  = GND
  CB1_A  = M_D_CPU1_SA_CB<1>
  VSS22  = GND
  DQS4_A_T  = M_D_CPU1_SA_DQS_DP<4>
  DQS4_A_C  = M_D_CPU1_SA_DQS_DN<4>
  VSS23  = GND
  CB4_A  = M_D_CPU1_SA_CB<4>
  VSS24  = GND
  CB5_A  = M_D_CPU1_SA_CB<5>
  VSS25  = GND
  ALERT_N  = M_D_CPU1_ALERT_N
  VSS26  = GND
  CS0_A_N  = M_D_CPU1_SA_CS_N<2>
  VSS27  = GND
  CA0_A  = M_D_CPU1_SA_CA<0>
  VSS28  = GND
  CA2_A  = M_D_CPU1_SA_CA<2>
  VSS29  = GND
  CA4_A  = M_D_CPU1_SA_CA<4>
  VSS30  = GND
  CA6_A  = M_D_CPU1_SA_CA<6>
  VSS31  = GND
  PAR_A  = M_D_CPU1_SA_PAR
  VSS32  = GND
  CA0_B  = M_D_CPU1_SB_CA<0>
  VSS33  = GND
  CA2_B  = M_D_CPU1_SB_CA<2>
  VSS34  = GND
  CA4_B  = M_D_CPU1_SB_CA<4>
  VSS35  = GND
  CA6_B  = M_D_CPU1_SB_CA<6>
  VSS36  = GND
  CS0_B_N  = M_D_CPU1_SB_CS_N<2>
  VSS37  = GND
  \lbd||rsp_a_n\  = M_D_CPU1_SA_RSP<1>
  \lbs||rsp_b_n\  = M_D_CPU1_SB_RSP<1>
  VSS38  = GND
  CB4_B  = M_D_CPU1_SB_CB<4>
  VSS39  = GND
  CB5_B  = M_D_CPU1_SB_CB<5>
  VSS40  = GND
  \dqs9_b_t||tdqs9_b_t||dbi4_b_n\  = M_D_CPU1_SB_DQS_DP<9>
  \dqs9_b_c||tdqs9_b_c\  = M_D_CPU1_SB_DQS_DN<9>
  VSS41  = GND
  CB0_B  = M_D_CPU1_SB_CB<0>
  VSS42  = GND
  CB1_B  = M_D_CPU1_SB_CB<1>
  VSS43  = GND
  DQ0_B  = M_D_CPU1_SB_DQ<0>
  VSS44  = GND
  DQ1_B  = M_D_CPU1_SB_DQ<1>
  VSS45  = GND
  DQS0_B_T  = M_D_CPU1_SB_DQS_DP<0>
  DQS0_B_C  = M_D_CPU1_SB_DQS_DN<0>
  VSS46  = GND
  DQ4_B  = M_D_CPU1_SB_DQ<4>
  VSS47  = GND
  DQ5_B  = M_D_CPU1_SB_DQ<5>
  VSS48  = GND
  DQ8_B  = M_D_CPU1_SB_DQ<8>
  VSS49  = GND
  DQ9_B  = M_D_CPU1_SB_DQ<9>
  VSS50  = GND
  DQS1_B_T  = M_D_CPU1_SB_DQS_DP<1>
  DQS1_B_C  = M_D_CPU1_SB_DQS_DN<1>
  VSS51  = GND
  DQ12_B  = M_D_CPU1_SB_DQ<12>
  VSS52  = GND
  DQ13_B  = M_D_CPU1_SB_DQ<13>
  VSS53  = GND
  DQ16_B  = M_D_CPU1_SB_DQ<16>
  VSS54  = GND
  DQ17_B  = M_D_CPU1_SB_DQ<17>
  VSS55  = GND
  DQS2_B_T  = M_D_CPU1_SB_DQS_DP<2>
  DQS2_B_C  = M_D_CPU1_SB_DQS_DN<2>
  VSS56  = GND
  DQ20_B  = M_D_CPU1_SB_DQ<20>
  VSS57  = GND
  DQ21_B  = M_D_CPU1_SB_DQ<21>
  VSS58  = GND
  DQ24_B  = M_D_CPU1_SB_DQ<24>
  VSS59  = GND
  DQ25_B  = M_D_CPU1_SB_DQ<25>
  VSS60  = GND
  DQS3_B_T  = M_D_CPU1_SB_DQS_DP<3>
  DQS3_B_C  = M_D_CPU1_SB_DQS_DN<3>
  VSS61  = GND
  DQ28_B  = M_D_CPU1_SB_DQ<28>
  VSS62  = GND
  DQ29_B  = M_D_CPU1_SB_DQ<29>
  VSS63  = GND
  RFU1  = TP_CHD_CPU1_DIMM2_FRU_1
  VIN_BULK1  = P12V_S3_AUX_CPU1_NVDIMM
  VIN_BULK2  = P12V_S3_AUX_CPU1_NVDIMM
  \pwr_good||fail_n\  = PWRGD_CHD_CPU1_DIMM2
  HSA  = PD_CHD_CPU1_DIMM2_SAA
  RFU2  = TP_CHD_CPU1_DIMM2_FRU_2
  RFU3  = TP_CHD_CPU1_DIMM2_FRU_3
  VSS64  = GND
  DQ2_A  = M_D_CPU1_SA_DQ<2>
  VSS65  = GND
  DQ3_A  = M_D_CPU1_SA_DQ<3>
  VSS66  = GND
  \dqs5_a_c||tdqs5_a_c||dqs5_a_t||tdqs5_a_t\  = M_D_CPU1_SA_DQS_DN<5>
  \dqs5_a_t||tdqs5_a_t\  = M_D_CPU1_SA_DQS_DP<5>
  VSS67  = GND
  DQ6_A  = M_D_CPU1_SA_DQ<6>
  VSS68  = GND
  DQ7_A  = M_D_CPU1_SA_DQ<7>
  VSS69  = GND
  DQ10_A  = M_D_CPU1_SA_DQ<10>
  VSS70  = GND
  DQ11_A  = M_D_CPU1_SA_DQ<11>
  VSS71  = GND
  \dqs6_a_c||tdqs6_a_c||dqs6_a_t||tdqs6_a_t\  = M_D_CPU1_SA_DQS_DN<6>
  \dqs6_a_t||tdqs6_a_t\  = M_D_CPU1_SA_DQS_DP<6>
  VSS72  = GND
  DQ14_A  = M_D_CPU1_SA_DQ<14>
  VSS73  = GND
  DQ15_A  = M_D_CPU1_SA_DQ<15>
  VSS74  = GND
  DQ18_A  = M_D_CPU1_SA_DQ<18>
  VSS75  = GND
  DQ19_A  = M_D_CPU1_SA_DQ<19>
  VSS76  = GND
  \dqs7_a_c||tdqs7_a_c\  = M_D_CPU1_SA_DQS_DN<7>
  \dqs7_a_t||tdqs7_a_t\  = M_D_CPU1_SA_DQS_DP<7>
  VSS77  = GND
  DQ22_A  = M_D_CPU1_SA_DQ<22>
  VSS78  = GND
  DQ23_A  = M_D_CPU1_SA_DQ<23>
  VSS79  = GND
  DQ26_A  = M_D_CPU1_SA_DQ<26>
  VSS80  = GND
  DQ27_A  = M_D_CPU1_SA_DQ<27>
  VSS81  = GND
  \dqs8_a_c||tdqs8_a_c\  = M_D_CPU1_SA_DQS_DN<8>
  \dqs8_a_t||tdqs8_a_t\  = M_D_CPU1_SA_DQS_DP<8>
  VSS82  = GND
  DQ30_A  = M_D_CPU1_SA_DQ<30>
  VSS83  = GND
  DQ31_A  = M_D_CPU1_SA_DQ<31>
  VSS84  = GND
  CB2_A  = M_D_CPU1_SA_CB<2>
  VSS85  = GND
  CB3_A  = M_D_CPU1_SA_CB<3>
  VSS86  = GND
  \dqs9_a_c||tdqs9_a_c\  = M_D_CPU1_SA_DQS_DN<9>
  \dqs9_a_t||tdqs9_a_t\  = M_D_CPU1_SA_DQS_DP<9>
  VSS87  = GND
  CB6_A  = M_D_CPU1_SA_CB<6>
  VSS88  = GND
  CB7_A  = M_D_CPU1_SA_CB<7>
  VSS89  = GND
  RESET_N  = RST_M_CD_CPU1_FPGA_N
  VSS90  = GND
  CS1_A_N  = M_D_CPU1_SA_CS_N<3>
  VSS91  = GND
  CA1_A  = M_D_CPU1_SA_CA<1>
  VSS92  = GND
  CA3_A  = M_D_CPU1_SA_CA<3>
  VSS93  = GND
  CA5_A  = M_D_CPU1_SA_CA<5>
  VSS94  = GND
  CK_T  = M_D_CPU1_CLK_DP<1>
  CK_C  = M_D_CPU1_CLK_DN<1>
  VSS95  = GND
  RFU4  = TP_CHD_CPU1_DIMM2_FRU_4
  CA1_B  = M_D_CPU1_SB_CA<1>
  VSS96  = GND
  CA3_B  = M_D_CPU1_SB_CA<3>
  VSS97  = GND
  CA5_B  = M_D_CPU1_SB_CA<5>
  VSS98  = GND
  PAR_B  = M_D_CPU1_SB_PAR
  VSS99  = GND
  CS1_B_N  = M_D_CPU1_SB_CS_N<3>
  VSS100  = GND
  RFU5  = TP_CHD_CPU1_DIMM2_FRU_5
  RFU6  = TP_CHD_CPU1_DIMM2_FRU_6
  VSS101  = GND
  CB6_B  = M_D_CPU1_SB_CB<6>
  VSS102  = GND
  CB7_B  = M_D_CPU1_SB_CB<7>
  VSS103  = GND
  DQS4_B_C  = M_D_CPU1_SB_DQS_DN<4>
  DQS4_B_T  = M_D_CPU1_SB_DQS_DP<4>
  VSS104  = GND
  CB2_B  = M_D_CPU1_SB_CB<2>
  VSS105  = GND
  CB3_B  = M_D_CPU1_SB_CB<3>
  VSS106  = GND
  DQ2_B  = M_D_CPU1_SB_DQ<2>
  VSS107  = GND
  DQ3_B  = M_D_CPU1_SB_DQ<3>
  VSS108  = GND
  \dqs5_b_c||tdqs5_b_c\  = M_D_CPU1_SB_DQS_DN<5>
  \dqs5_b_t||tdqs5_b_t\  = M_D_CPU1_SB_DQS_DP<5>
  VSS109  = GND
  DQ6_B  = M_D_CPU1_SB_DQ<6>
  VSS110  = GND
  DQ7_B  = M_D_CPU1_SB_DQ<7>
  VSS111  = GND
  DQ10_B  = M_D_CPU1_SB_DQ<10>
  VSS112  = GND
  DQ11_B  = M_D_CPU1_SB_DQ<11>
  VSS113  = GND
  \dqs6_b_c||tdqs6_b_c\  = M_D_CPU1_SB_DQS_DN<6>
  \dqs6_b_t||tdqs6_b_t\  = M_D_CPU1_SB_DQS_DP<6>
  VSS114  = GND
  DQ14_B  = M_D_CPU1_SB_DQ<14>
  VSS115  = GND
  DQ15_B  = M_D_CPU1_SB_DQ<15>
  VSS116  = GND
  DQ18_B  = M_D_CPU1_SB_DQ<18>
  VSS117  = GND
  DQ19_B  = M_D_CPU1_SB_DQ<19>
  VSS118  = GND
  \dqs7_b_c||tdqs7_b_c\  = M_D_CPU1_SB_DQS_DN<7>
  \dqs7_b_t||tdqs7_b_t\  = M_D_CPU1_SB_DQS_DP<7>
  VSS119  = GND
  DQ22_B  = M_D_CPU1_SB_DQ<22>
  VSS120  = GND
  DQ23_B  = M_D_CPU1_SB_DQ<23>
  VSS121  = GND
  DQ26_B  = M_D_CPU1_SB_DQ<26>
  VSS122  = GND
  DQ27_B  = M_D_CPU1_SB_DQ<27>
  VSS123  = GND
  \dqs8_b_c||tdqs8_b_c\  = M_D_CPU1_SB_DQS_DN<8>
  \dqs8_b_t||tdqs8_b_t\  = M_D_CPU1_SB_DQS_DP<8>
  VSS124  = GND
  DQ30_B  = M_D_CPU1_SB_DQ<30>
  VSS125  = GND
  DQ31_B  = M_D_CPU1_SB_DQ<31>
  VSS126  = GND
  G1  = GND
  G2  = GND
  G3  = GND

(kicad_pcb
	(version 20260206)
	(generator "pcbnew")
	(generator_version "10.0")
	(general
		(thickness 1.6)
		(legacy_teardrops no)
	)
	(paper "A4")
	(title_block
		(title "03242023_DA0F0TMBIJ0_F0T_Motherboard_J_brd_V01_OCP.brd")
		(comment 1 "Grand Teton / footprint 1660 of 6105 (J24), pads 183-228 of 291")
	)
	(layers
		(0 "F.Cu" signal "TOP")
		(4 "In1.Cu" signal "GND")
		(6 "In2.Cu" signal "IN1")
		(8 "In3.Cu" signal "GND1")
		(10 "In4.Cu" signal "IN2")
		(12 "In5.Cu" signal "GND2")
		(14 "In6.Cu" signal "IN3")
		(16 "In7.Cu" signal "GND3")
		(18 "In8.Cu" signal "VCC")
		(20 "In9.Cu" signal "VCC1")
		(22 "In10.Cu" signal "GND4")
		(24 "In11.Cu" signal "IN4")
		(26 "In12.Cu" signal "GND5")
		(28 "In13.Cu" signal "IN5")
		(30 "In14.Cu" signal "GND6")
		(32 "In15.Cu" signal "IN6")
		(34 "In16.Cu" signal "GND7")
		(2 "B.Cu" signal "BOTTOM")
		(9 "F.Adhes" user "F.Adhesive")
		(11 "B.Adhes" user "B.Adhesive")
		(13 "F.Paste" user "Package Geometry/Pastemask Top")
		(15 "B.Paste" user "Package Geometry/Pastemask Bottom")
		(5 "F.SilkS" user "Ref Des/Silkscreen Top")
		(7 "B.SilkS" user "Ref Des/Silkscreen Bottom")
		(1 "F.Mask" user "Board Geometry/Soldermask Top")
		(3 "B.Mask" user "Board Geometry/Soldermask Bottom")
		(17 "Dwgs.User" user "User.Drawings")
		(19 "Cmts.User" user "User.Comments")
		(21 "Eco1.User" user "User.Eco1")
		(23 "Eco2.User" user "User.Eco2")
		(25 "Edge.Cuts" user "Board Geometry/Outline")
		(27 "Margin" user)
		(31 "F.CrtYd" user "Package Geometry/Place Bound Top")
		(29 "B.CrtYd" user "Package Geometry/Place Bound Bottom")
		(35 "F.Fab" user "Ref Des/Assembly Top")
		(33 "B.Fab" user "Ref Des/Assembly Bottom")
	)
	(footprint ""
		(layer "F.Cu")
		(at 17.73428 -258.091686)
		(property "Reference" "J24"
			(at -3.0607 -81.901792 0)
			(unlocked yes)
			(layer "F.SilkS")
			(effects
				(font
					(size 0.7874 0.5842)
					(thickness 0.1524)
				)
				(justify left)
			)
		)
		(property "Value" ""
			(at 0 0 0)
			(layer "F.Fab")
			(effects
				(font
					(size 1.27 1.27)
				)
			)
		)
		(duplicate_pad_numbers_are_jumpers no)
		(pad "183" smd rect
			(at 2.050034 -31.025084 270)
			(size 0.519938 1.4986)
			(layers "F.Cu" "F.Mask" "F.Paste")
			(net "M_D_CPU1_SA_DQ<23>")
		)
		(pad "184" smd rect
			(at 2.050034 -30.174946 270)
			(size 0.519938 1.4986)
			(layers "F.Cu" "F.Mask" "F.Paste")
			(net "GND")
		)
		(pad "185" smd rect
			(at 2.050034 -29.325062 270)
			(size 0.519938 1.4986)
			(layers "F.Cu" "F.Mask" "F.Paste")
			(net "M_D_CPU1_SA_DQ<26>")
		)
		(pad "186" smd rect
			(at 2.050034 -28.474924 270)
			(size 0.519938 1.4986)
			(layers "F.Cu" "F.Mask" "F.Paste")
			(net "GND")
		)
		(pad "187" smd rect
			(at 2.050034 -27.62504 270)
			(size 0.519938 1.4986)
			(layers "F.Cu" "F.Mask" "F.Paste")
			(net "M_D_CPU1_SA_DQ<27>")
		)
		(pad "188" smd rect
			(at 2.050034 -26.774902 270)
			(size 0.519938 1.4986)
			(layers "F.Cu" "F.Mask" "F.Paste")
			(net "GND")
		)
		(pad "189" smd rect
			(at 2.050034 -25.925018 270)
			(size 0.519938 1.4986)
			(layers "F.Cu" "F.Mask" "F.Paste")
			(net "M_D_CPU1_SA_DQS_DN<8>")
		)
		(pad "190" smd rect
			(at 2.050034 -25.07488 270)
			(size 0.519938 1.4986)
			(layers "F.Cu" "F.Mask" "F.Paste")
			(net "M_D_CPU1_SA_DQS_DP<8>")
		)
		(pad "191" smd rect
			(at 2.050034 -24.224996 270)
			(size 0.519938 1.4986)
			(layers "F.Cu" "F.Mask" "F.Paste")
			(net "GND")
		)
		(pad "192" smd rect
			(at 2.050034 -23.375112 270)
			(size 0.519938 1.4986)
			(layers "F.Cu" "F.Mask" "F.Paste")
			(net "M_D_CPU1_SA_DQ<30>")
		)
		(pad "193" smd rect
			(at 2.050034 -22.524974 270)
			(size 0.519938 1.4986)
			(layers "F.Cu" "F.Mask" "F.Paste")
			(net "GND")
		)
		(pad "194" smd rect
			(at 2.050034 -21.67509 270)
			(size 0.519938 1.4986)
			(layers "F.Cu" "F.Mask" "F.Paste")
			(net "M_D_CPU1_SA_DQ<31>")
		)
		(pad "195" smd rect
			(at 2.050034 -20.824952 270)
			(size 0.519938 1.4986)
			(layers "F.Cu" "F.Mask" "F.Paste")
			(net "GND")
		)
		(pad "196" smd rect
			(at 2.050034 -19.975068 270)
			(size 0.519938 1.4986)
			(layers "F.Cu" "F.Mask" "F.Paste")
			(net "M_D_CPU1_SA_CB<2>")
		)
		(pad "197" smd rect
			(at 2.050034 -19.12493 270)
			(size 0.519938 1.4986)
			(layers "F.Cu" "F.Mask" "F.Paste")
			(net "GND")
		)
		(pad "198" smd rect
			(at 2.050034 -18.275046 270)
			(size 0.519938 1.4986)
			(layers "F.Cu" "F.Mask" "F.Paste")
			(net "M_D_CPU1_SA_CB<3>")
		)
		(pad "199" smd rect
			(at 2.050034 -17.424908 270)
			(size 0.519938 1.4986)
			(layers "F.Cu" "F.Mask" "F.Paste")
			(net "GND")
		)
		(pad "200" smd rect
			(at 2.050034 -16.575024 270)
			(size 0.519938 1.4986)
			(layers "F.Cu" "F.Mask" "F.Paste")
			(net "M_D_CPU1_SA_DQS_DN<9>")
		)
		(pad "201" smd rect
			(at 2.050034 -15.724886 270)
			(size 0.519938 1.4986)
			(layers "F.Cu" "F.Mask" "F.Paste")
			(net "M_D_CPU1_SA_DQS_DP<9>")
		)
		(pad "202" smd rect
			(at 2.050034 -14.875002 270)
			(size 0.519938 1.4986)
			(layers "F.Cu" "F.Mask" "F.Paste")
			(net "GND")
		)
		(pad "203" smd rect
			(at 2.050034 -14.025118 270)
			(size 0.519938 1.4986)
			(layers "F.Cu" "F.Mask" "F.Paste")
			(net "M_D_CPU1_SA_CB<6>")
		)
		(pad "204" smd rect
			(at 2.050034 -13.17498 270)
			(size 0.519938 1.4986)
			(layers "F.Cu" "F.Mask" "F.Paste")
			(net "GND")
		)
		(pad "205" smd rect
			(at 2.050034 -12.325096 270)
			(size 0.519938 1.4986)
			(layers "F.Cu" "F.Mask" "F.Paste")
			(net "M_D_CPU1_SA_CB<7>")
		)
		(pad "206" smd rect
			(at 2.050034 -11.474958 270)
			(size 0.519938 1.4986)
			(layers "F.Cu" "F.Mask" "F.Paste")
			(net "GND")
		)
		(pad "207" smd rect
			(at 2.050034 -10.625074 270)
			(size 0.519938 1.4986)
			(layers "F.Cu" "F.Mask" "F.Paste")
			(net "RST_M_CD_CPU1_FPGA_N")
		)
		(pad "208" smd rect
			(at 2.050034 -9.774936 270)
			(size 0.519938 1.4986)
			(layers "F.Cu" "F.Mask" "F.Paste")
			(net "GND")
		)
		(pad "209" smd rect
			(at 2.050034 -8.925052 270)
			(size 0.519938 1.4986)
			(layers "F.Cu" "F.Mask" "F.Paste")
			(net "M_D_CPU1_SA_CS_N<3>")
		)
		(pad "210" smd rect
			(at 2.050034 -8.074914 270)
			(size 0.519938 1.4986)
			(layers "F.Cu" "F.Mask" "F.Paste")
			(net "GND")
		)
		(pad "211" smd rect
			(at 2.050034 -7.22503 270)
			(size 0.519938 1.4986)
			(layers "F.Cu" "F.Mask" "F.Paste")
			(net "M_D_CPU1_SA_CA<1>")
		)
		(pad "212" smd rect
			(at 2.050034 -6.374892 270)
			(size 0.519938 1.4986)
			(layers "F.Cu" "F.Mask" "F.Paste")
			(net "GND")
		)
		(pad "213" smd rect
			(at 2.050034 -5.525008 270)
			(size 0.519938 1.4986)
			(layers "F.Cu" "F.Mask" "F.Paste")
			(net "M_D_CPU1_SA_CA<3>")
		)
		(pad "214" smd rect
			(at 2.050034 -4.675124 270)
			(size 0.519938 1.4986)
			(layers "F.Cu" "F.Mask" "F.Paste")
			(net "GND")
		)
		(pad "215" smd rect
			(at 2.050034 -3.824986 270)
			(size 0.519938 1.4986)
			(layers "F.Cu" "F.Mask" "F.Paste")
			(net "M_D_CPU1_SA_CA<5>")
		)
		(pad "216" smd rect
			(at 2.050034 -2.975102 270)
			(size 0.519938 1.4986)
			(layers "F.Cu" "F.Mask" "F.Paste")
			(net "GND")
		)
		(pad "217" smd rect
			(at 2.050034 -2.124964 270)
			(size 0.519938 1.4986)
			(layers "F.Cu" "F.Mask" "F.Paste")
			(net "M_D_CPU1_CLK_DP<1>")
		)
		(pad "218" smd rect
			(at 2.050034 -1.27508 270)
			(size 0.519938 1.4986)
			(layers "F.Cu" "F.Mask" "F.Paste")
			(net "M_D_CPU1_CLK_DN<1>")
		)
		(pad "219" smd rect
			(at 2.050034 -0.424942 270)
			(size 0.519938 1.4986)
			(layers "F.Cu" "F.Mask" "F.Paste")
			(net "GND")
		)
		(pad "220" smd rect
			(at 2.050034 5.525008 270)
			(size 0.519938 1.4986)
			(layers "F.Cu" "F.Mask" "F.Paste")
			(net "TP_CHD_CPU1_DIMM2_FRU_4")
		)
		(pad "221" smd rect
			(at 2.050034 6.374892 270)
			(size 0.519938 1.4986)
			(layers "F.Cu" "F.Mask" "F.Paste")
			(net "M_D_CPU1_SB_CA<1>")
		)
		(pad "222" smd rect
			(at 2.050034 7.22503 270)
			(size 0.519938 1.4986)
			(layers "F.Cu" "F.Mask" "F.Paste")
			(net "GND")
		)
		(pad "223" smd rect
			(at 2.050034 8.074914 270)
			(size 0.519938 1.4986)
			(layers "F.Cu" "F.Mask" "F.Paste")
			(net "M_D_CPU1_SB_CA<3>")
		)
		(pad "224" smd rect
			(at 2.050034 8.925052 270)
			(size 0.519938 1.4986)
			(layers "F.Cu" "F.Mask" "F.Paste")
			(net "GND")
		)
		(pad "225" smd rect
			(at 2.050034 9.774936 270)
			(size 0.519938 1.4986)
			(layers "F.Cu" "F.Mask" "F.Paste")
			(net "M_D_CPU1_SB_CA<5>")
		)
		(pad "226" smd rect
			(at 2.050034 10.625074 270)
			(size 0.519938 1.4986)
			(layers "F.Cu" "F.Mask" "F.Paste")
			(net "GND")
		)
		(pad "227" smd rect
			(at 2.050034 11.474958 270)
			(size 0.519938 1.4986)
			(layers "F.Cu" "F.Mask" "F.Paste")
			(net "M_D_CPU1_SB_PAR")
		)
		(pad "228" smd rect
			(at 2.050034 12.325096 270)
			(size 0.519938 1.4986)
			(layers "F.Cu" "F.Mask" "F.Paste")
			(net "GND")
		)
	)
)
